(kicad_pcb
	(version 20260206)
	(generator "pcbnew")
	(generator_version "10.0")
	(general
		(thickness 1.6)
		(legacy_teardrops no)
	)
	(paper "A4")
	(title_block
		(title "Bryce Canyon_IOM_IOC_16318-2_OCP.brd")
		(comment 1 "Bryce Canyon / footprints 151-156 of 1605")
	)
	(layers
		(0 "F.Cu" signal "TOP")
		(4 "In1.Cu" signal "L2GND")
		(6 "In2.Cu" signal "L3")
		(8 "In3.Cu" signal "L4VCC")
		(10 "In4.Cu" signal "L5VCC")
		(12 "In5.Cu" signal "L6")
		(14 "In6.Cu" signal "L7GND")
		(2 "B.Cu" signal "BOTTOM")
		(9 "F.Adhes" user "F.Adhesive")
		(11 "B.Adhes" user "B.Adhesive")
		(13 "F.Paste" user "Package Geometry/Pastemask Top")
		(15 "B.Paste" user "Package Geometry/Pastemask Bottom")
		(5 "F.SilkS" user "Ref Des/Silkscreen Top")
		(7 "B.SilkS" user "Ref Des/Silkscreen Bottom")
		(1 "F.Mask" user "Board Geometry/Soldermask Top")
		(3 "B.Mask" user "Board Geometry/Soldermask Bottom")
		(17 "Dwgs.User" user "User.Drawings")
		(19 "Cmts.User" user "User.Comments")
		(21 "Eco1.User" user "User.Eco1")
		(23 "Eco2.User" user "User.Eco2")
		(25 "Edge.Cuts" user "Board Geometry/Outline")
		(27 "Margin" user)
		(31 "F.CrtYd" user "Package Geometry/Place Bound Top")
		(29 "B.CrtYd" user "Package Geometry/Place Bound Bottom")
		(35 "F.Fab" user "Ref Des/Assembly Top")
		(33 "B.Fab" user "Ref Des/Assembly Bottom")
	)
	(footprint ""
		(layer "F.Cu")
		(at 208.055972 -73.3552 90)
		(property "Reference" "C311"
			(at 0 0 90)
			(layer "F.SilkS")
			(hide yes)
			(effects
				(font
					(size 1.27 1.27)
				)
			)
		)
		(property "Value" "SCD01U16V1KX-GP"
			(at -2.8321 -1.7399 90)
			(unlocked yes)
			(layer "F.Fab")
			(hide yes)
			(effects
				(font
					(size 1.016 1.016)
					(thickness 0.1524)
				)
			)
		)
		(property "Device Type" "C0201H13"
			(at -2.8321 -3.2639 90)
			(unlocked yes)
			(layer "F.Fab")
			(hide yes)
			(effects
				(font
					(size 1.016 1.016)
					(thickness 0.1524)
				)
			)
		)
		(duplicate_pad_numbers_are_jumpers no)
		(fp_rect
			(start -0.2794 0.6477)
			(end 0.2794 -0.6477)
			(stroke
				(width 0)
				(type default)
			)
			(fill no)
			(layer "F.CrtYd")
		)
		(fp_rect
			(start -0.2794 0.6477)
			(end 0.2794 -0.6477)
			(stroke
				(width 0)
				(type default)
			)
			(fill no)
			(layer "F.Fab")
		)
		(pad "1" smd custom
			(at 0 -0.2794 90)
			(size 0.0762 0.0762)
			(layers "F.Cu" "F.Mask" "F.Paste")
			(net "PHY_IOC_TO_CON_A_2_DP_C")
			(options
				(clearance outline)
				(anchor circle)
			)
			(primitives
				(gr_poly
					(pts
						(arc
							(start 0.1524 -0.127)
							(mid 0.137521 -0.162921)
							(end 0.1016 -0.1778)
						)
						(arc
							(start -0.1016 -0.1778)
							(mid -0.137521 -0.162921)
							(end -0.1524 -0.127)
						)
						(arc
							(start -0.1524 0.127)
							(mid -0.137521 0.162921)
							(end -0.1016 0.1778)
						)
						(arc
							(start 0.1016 0.1778)
							(mid 0.137521 0.162921)
							(end 0.1524 0.127)
						)
					)
					(width 0)
					(fill yes)
				)
			)
		)
		(pad "2" smd custom
			(at 0 0.2794 90)
			(size 0.0762 0.0762)
			(layers "F.Cu" "F.Mask" "F.Paste")
			(net "PHY_IOC_TO_CON_A_2_DP")
			(options
				(clearance outline)
				(anchor circle)
			)
			(primitives
				(gr_poly
					(pts
						(arc
							(start 0.1524 -0.127)
							(mid 0.137521 -0.162921)
							(end 0.1016 -0.1778)
						)
						(arc
							(start -0.1016 -0.1778)
							(mid -0.137521 -0.162921)
							(end -0.1524 -0.127)
						)
						(arc
							(start -0.1524 0.127)
							(mid -0.137521 0.162921)
							(end -0.1016 0.1778)
						)
						(arc
							(start 0.1016 0.1778)
							(mid 0.137521 0.162921)
							(end 0.1524 0.127)
						)
					)
					(width 0)
					(fill yes)
				)
			)
		)
	)
	(footprint ""
		(layer "F.Cu")
		(at 43.942 -161.3662 180)
		(property "Reference" "R188"
			(at 0 0 180)
			(layer "F.SilkS")
			(hide yes)
			(effects
				(font
					(size 1.27 1.27)
				)
			)
		)
		(property "Value" "2K2R2F-GP"
			(at 0.064008 -3.993896 180)
			(unlocked yes)
			(layer "F.Fab")
			(hide yes)
			(effects
				(font
					(size 1.016 1.016)
					(thickness 0.1524)
				)
			)
		)
		(property "Device Type" "R402H16"
			(at 0.064008 -5.517896 180)
			(unlocked yes)
			(layer "F.Fab")
			(hide yes)
			(effects
				(font
					(size 1.016 1.016)
					(thickness 0.1524)
				)
			)
		)
		(duplicate_pad_numbers_are_jumpers no)
		(fp_line
			(start 0.508 -0.9398)
			(end -0.508 -0.9398)
			(stroke
				(width 0.1524)
				(type default)
			)
			(layer "F.SilkS")
		)
		(fp_line
			(start -0.508 -0.9398)
			(end -0.508 0.9398)
			(stroke
				(width 0.1524)
				(type default)
			)
			(layer "F.SilkS")
		)
		(fp_rect
			(start -0.508 0.9398)
			(end 0.508 -0.9398)
			(stroke
				(width 0)
				(type default)
			)
			(fill no)
			(layer "F.CrtYd")
		)
		(fp_rect
			(start -0.508 0.9398)
			(end 0.508 -0.9398)
			(stroke
				(width 0)
				(type default)
			)
			(fill no)
			(layer "F.Fab")
		)
		(pad "1" smd custom
			(at 0 -0.4445 180)
			(size 0.1397 0.1397)
			(layers "F.Cu" "F.Mask" "F.Paste")
			(net "I2C_M2_1_SDA")
			(options
				(clearance outline)
				(anchor circle)
			)
			(primitives
				(gr_poly
					(pts
						(arc
							(start -0.1778 -0.2794)
							(mid -0.249642 -0.249642)
							(end -0.2794 -0.1778)
						)
						(arc
							(start -0.2794 0.1778)
							(mid -0.249642 0.249642)
							(end -0.1778 0.2794)
						)
						(arc
							(start 0.1778 0.2794)
							(mid 0.249642 0.249642)
							(end 0.2794 0.1778)
						)
						(arc
							(start 0.2794 -0.1778)
							(mid 0.249642 -0.249642)
							(end 0.1778 -0.2794)
						)
					)
					(width 0)
					(fill yes)
				)
			)
		)
		(pad "2" smd custom
			(at 0 0.4445 180)
			(size 0.1397 0.1397)
			(layers "F.Cu" "F.Mask" "F.Paste")
			(net "P3V3_STBY")
			(options
				(clearance outline)
				(anchor circle)
			)
			(primitives
				(gr_poly
					(pts
						(arc
							(start -0.1778 -0.2794)
							(mid -0.249642 -0.249642)
							(end -0.2794 -0.1778)
						)
						(arc
							(start -0.2794 0.1778)
							(mid -0.249642 0.249642)
							(end -0.1778 0.2794)
						)
						(arc
							(start 0.1778 0.2794)
							(mid 0.249642 0.249642)
							(end 0.2794 0.1778)
						)
						(arc
							(start 0.2794 -0.1778)
							(mid 0.249642 -0.249642)
							(end 0.1778 -0.2794)
						)
					)
					(width 0)
					(fill yes)
				)
			)
		)
	)
	(footprint ""
		(layer "F.Cu")
		(at 26.90368 -122.859292 180)
		(property "Reference" "R84"
			(at 0 0 180)
			(layer "F.SilkS")
			(hide yes)
			(effects
				(font
					(size 1.27 1.27)
				)
			)
		)
		(property "Value" "4K7R2F-GP"
			(at 0.064008 -3.993896 180)
			(unlocked yes)
			(layer "F.Fab")
			(hide yes)
			(effects
				(font
					(size 1.016 1.016)
					(thickness 0.1524)
				)
			)
		)
		(property "Device Type" "R402H16"
			(at 0.064008 -5.517896 180)
			(unlocked yes)
			(layer "F.Fab")
			(hide yes)
			(effects
				(font
					(size 1.016 1.016)
					(thickness 0.1524)
				)
			)
		)
		(duplicate_pad_numbers_are_jumpers no)
		(fp_line
			(start 0.508 -0.9398)
			(end -0.508 -0.9398)
			(stroke
				(width 0.1524)
				(type default)
			)
			(layer "F.SilkS")
		)
		(fp_line
			(start -0.508 -0.9398)
			(end -0.508 0.9398)
			(stroke
				(width 0.1524)
				(type default)
			)
			(layer "F.SilkS")
		)
		(fp_rect
			(start -0.508 0.9398)
			(end 0.508 -0.9398)
			(stroke
				(width 0)
				(type default)
			)
			(fill no)
			(layer "F.CrtYd")
		)
		(fp_rect
			(start -0.508 0.9398)
			(end 0.508 -0.9398)
			(stroke
				(width 0)
				(type default)
			)
			(fill no)
			(layer "F.Fab")
		)
		(pad "1" smd custom
			(at 0 -0.4445 180)
			(size 0.1397 0.1397)
			(layers "F.Cu" "F.Mask" "F.Paste")
			(net "P3V3_STBY")
			(options
				(clearance outline)
				(anchor circle)
			)
			(primitives
				(gr_poly
					(pts
						(arc
							(start -0.1778 -0.2794)
							(mid -0.249642 -0.249642)
							(end -0.2794 -0.1778)
						)
						(arc
							(start -0.2794 0.1778)
							(mid -0.249642 0.249642)
							(end -0.1778 0.2794)
						)
						(arc
							(start 0.1778 0.2794)
							(mid 0.249642 0.249642)
							(end 0.2794 0.1778)
						)
						(arc
							(start 0.2794 -0.1778)
							(mid 0.249642 -0.249642)
							(end 0.1778 -0.2794)
						)
					)
					(width 0)
					(fill yes)
				)
			)
		)
		(pad "2" smd custom
			(at 0 0.4445 180)
			(size 0.1397 0.1397)
			(layers "F.Cu" "F.Mask" "F.Paste")
			(net "WP_DISABLE")
			(options
				(clearance outline)
				(anchor circle)
			)
			(primitives
				(gr_poly
					(pts
						(arc
							(start -0.1778 -0.2794)
							(mid -0.249642 -0.249642)
							(end -0.2794 -0.1778)
						)
						(arc
							(start -0.2794 0.1778)
							(mid -0.249642 0.249642)
							(end -0.1778 0.2794)
						)
						(arc
							(start 0.1778 0.2794)
							(mid 0.249642 0.249642)
							(end 0.2794 0.1778)
						)
						(arc
							(start 0.2794 -0.1778)
							(mid 0.249642 -0.249642)
							(end 0.1778 -0.2794)
						)
					)
					(width 0)
					(fill yes)
				)
			)
		)
	)
	(footprint ""
		(layer "F.Cu")
		(at 185.42 -49.9872)
		(property "Reference" "TP162"
			(at 0 0 0)
			(layer "F.SilkS")
			(hide yes)
			(effects
				(font
					(size 1.27 1.27)
				)
			)
		)
		(property "Value" "TPAD28-2-GP"
			(at -0.0127 -1.6637 0)
			(unlocked yes)
			(layer "F.Fab")
			(hide yes)
			(effects
				(font
					(size 1.016 1.016)
					(thickness 0.1524)
				)
			)
		)
		(property "Device Type" "TPAD28"
			(at -0.0127 -3.1877 0)
			(unlocked yes)
			(layer "F.Fab")
			(hide yes)
			(effects
				(font
					(size 1.016 1.016)
					(thickness 0.1524)
				)
			)
		)
		(duplicate_pad_numbers_are_jumpers no)
		(fp_poly
			(pts
				(arc
					(start 0.3556 0)
					(mid -0.3556 0)
					(end 0.3556 0)
				)
			)
			(stroke
				(width 0)
				(type default)
			)
			(fill no)
			(layer "F.CrtYd")
		)
		(fp_poly
			(pts
				(arc
					(start 0.6096 0)
					(mid -0.6096 0)
					(end 0.6096 0)
				)
			)
			(stroke
				(width 0)
				(type default)
			)
			(fill no)
			(layer "F.Fab")
		)
		(pad "1" smd circle
			(at 0 0)
			(size 0.7112 0.7112)
			(layers "F.Cu" "F.Mask" "F.Paste")
			(net "XM_ADDR_0")
		)
	)
	(footprint ""
		(layer "F.Cu")
		(at 36.76904 -121.360946 -90)
		(property "Reference" "SKT1"
			(at 0 0 270)
			(layer "F.SilkS")
			(hide yes)
			(effects
				(font
					(size 1.27 1.27)
				)
			)
		)
		(property "Value" "SKT-SPI16P-GP-U"
			(at -8.9916 4.641596 270)
			(unlocked yes)
			(layer "F.Fab")
			(hide yes)
			(effects
				(font
					(size 1.016 1.016)
					(thickness 0.1524)
				)
			)
		)
		(property "Device Type" "SKT-SOIC16-153139H258"
			(at -8.9916 3.117596 270)
			(unlocked yes)
			(layer "F.Fab")
			(hide yes)
			(effects
				(font
					(size 1.016 1.016)
					(thickness 0.1524)
				)
			)
		)
		(duplicate_pad_numbers_are_jumpers no)
		(fp_line
			(start -7.8994 6.4008)
			(end 7.8994 6.4008)
			(stroke
				(width 0.1524)
				(type default)
			)
			(layer "F.SilkS")
		)
		(fp_line
			(start 7.8994 6.4008)
			(end 7.8994 -6.4008)
			(stroke
				(width 0.1524)
				(type default)
			)
			(layer "F.SilkS")
		)
		(fp_line
			(start 6.7183 0.0762)
			(end 7.8994 1.2573)
			(stroke
				(width 0.1524)
				(type default)
			)
			(layer "F.SilkS")
		)
		(fp_line
			(start 7.8867 -1.0922)
			(end 6.7183 0.0762)
			(stroke
				(width 0.1524)
				(type default)
			)
			(layer "F.SilkS")
		)
		(fp_line
			(start 7.7216 -6.223)
			(end 7.7216 -3.6576)
			(stroke
				(width 0.508)
				(type default)
			)
			(layer "F.SilkS")
		)
		(fp_line
			(start -7.8994 -6.4008)
			(end -7.8994 6.4008)
			(stroke
				(width 0.1524)
				(type default)
			)
			(layer "F.SilkS")
		)
		(fp_line
			(start 7.8994 -6.4008)
			(end -7.8994 -6.4008)
			(stroke
				(width 0.1524)
				(type default)
			)
			(layer "F.SilkS")
		)
		(fp_poly
			(pts
				(xy -4.699 -3.855466) (xy -4.699 3.855466) (xy 4.699 3.855466) (xy 4.699 -3.855466)
			)
			(stroke
				(width 0)
				(type default)
			)
			(fill yes)
			(layer "F.SilkS")
		)
		(fp_rect
			(start -8.1534 11.6078)
			(end 8.1534 6.4008)
			(stroke
				(width 0)
				(type default)
			)
			(fill no)
			(layer "F.CrtYd")
		)
		(fp_rect
			(start -8.1534 -6.4008)
			(end 8.1534 -12.5222)
			(stroke
				(width 0)
				(type default)
			)
			(fill no)
			(layer "F.CrtYd")
		)
		(fp_poly
			(pts
				(xy -8.1534 6.4008) (xy -8.1534 -6.4008) (xy -6.2484 -6.4008) (xy -6.2484 -2.6416) (xy -7.6454 -2.6416)
				(xy -7.6454 2.6416) (xy -6.2484 2.6416) (xy -6.2484 6.4008)
			)
			(stroke
				(width 0)
				(type default)
			)
			(fill no)
			(layer "F.CrtYd")
		)
		(fp_poly
			(pts
				(xy 6.2484 -6.4008) (xy 8.1534 -6.4008) (xy 8.1534 6.4008) (xy 6.2484 6.4008) (xy 6.2484 2.6416)
				(xy 7.6454 2.6416) (xy 7.6454 -2.6416) (xy 6.2484 -2.6416)
			)
			(stroke
				(width 0)
				(type default)
			)
			(fill no)
			(layer "F.CrtYd")
		)
		(fp_poly
			(pts
				(xy 6.2484 -6.4008) (xy -6.2484 -6.4008) (xy -6.2484 -2.6416) (xy -7.6454 -2.6416) (xy -7.6454 2.6416)
				(xy -6.2484 2.6416) (xy -6.2484 6.4008) (xy 6.2484 6.4008) (xy 6.2484 2.6416) (xy 7.6454 2.6416)
				(xy 7.6454 -2.6416) (xy 6.2484 -2.6416)
			)
			(stroke
				(width 0)
				(type default)
			)
			(fill no)
			(layer "F.CrtYd")
		)
		(fp_rect
			(start -8.1534 11.6078)
			(end 8.1534 -12.5222)
			(stroke
				(width 0)
				(type default)
			)
			(fill no)
			(layer "F.Fab")
		)
		(pad "1" smd rect
			(at 4.445 -4.896866 270)
			(size 0.508 1.6764)
			(layers "F.Cu" "F.Mask" "F.Paste")
			(net "FLA0_SPI_HOLD_N")
		)
		(pad "2" smd rect
			(at 3.175 -4.896866 270)
			(size 0.508 1.6764)
			(layers "F.Cu" "F.Mask" "F.Paste")
			(net "P3V3_STBY")
		)
		(pad "3" smd rect
			(at 1.905 -4.896866 270)
			(size 0.508 1.6764)
			(layers "F.Cu" "F.Mask" "F.Paste")
			(net "FLA0_SPI_RST")
		)
		(pad "4" smd rect
			(at 0.635 -4.896866 270)
			(size 0.508 1.6764)
			(layers "F.Cu" "F.Mask" "F.Paste")
			(net "Net_1257")
		)
		(pad "5" smd rect
			(at -0.635 -4.896866 270)
			(size 0.508 1.6764)
			(layers "F.Cu" "F.Mask" "F.Paste")
			(net "Net_1256")
		)
		(pad "6" smd rect
			(at -1.905 -4.896866 270)
			(size 0.508 1.6764)
			(layers "F.Cu" "F.Mask" "F.Paste")
			(net "Net_1255")
		)
		(pad "7" smd rect
			(at -3.175 -4.896866 270)
			(size 0.508 1.6764)
			(layers "F.Cu" "F.Mask" "F.Paste")
			(net "FLA_CS_0_R")
		)
		(pad "8" smd rect
			(at -4.445 -4.896866 270)
			(size 0.508 1.6764)
			(layers "F.Cu" "F.Mask" "F.Paste")
			(net "BMC_SPI_MISO_TPM")
		)
		(pad "9" smd rect
			(at -4.445 4.896866 270)
			(size 0.508 1.6764)
			(layers "F.Cu" "F.Mask" "F.Paste")
			(net "FLA0_WP_N")
		)
		(pad "10" smd rect
			(at -3.175 4.896866 270)
			(size 0.508 1.6764)
			(layers "F.Cu" "F.Mask" "F.Paste")
			(net "GND")
		)
		(pad "11" smd rect
			(at -1.905 4.896866 270)
			(size 0.508 1.6764)
			(layers "F.Cu" "F.Mask" "F.Paste")
			(net "Net_1261")
		)
		(pad "12" smd rect
			(at -0.635 4.896866 270)
			(size 0.508 1.6764)
			(layers "F.Cu" "F.Mask" "F.Paste")
			(net "Net_1260")
		)
		(pad "13" smd rect
			(at 0.635 4.896866 270)
			(size 0.508 1.6764)
			(layers "F.Cu" "F.Mask" "F.Paste")
			(net "Net_1259")
		)
		(pad "14" smd rect
			(at 1.905 4.896866 270)
			(size 0.508 1.6764)
			(layers "F.Cu" "F.Mask" "F.Paste")
			(net "Net_1258")
		)
		(pad "15" smd rect
			(at 3.175 4.896866 270)
			(size 0.508 1.6764)
			(layers "F.Cu" "F.Mask" "F.Paste")
			(net "BMC_SPI_MOSI_R")
		)
		(pad "16" smd rect
			(at 4.445 4.896866 270)
			(size 0.508 1.6764)
			(layers "F.Cu" "F.Mask" "F.Paste")
			(net "BMC_SPI_CLK_R")
		)
	)
	(footprint ""
		(layer "F.Cu")
		(at 220.2815 -102.4636 90)
		(property "Reference" "R604"
			(at 0 0 90)
			(layer "F.SilkS")
			(hide yes)
			(effects
				(font
					(size 1.27 1.27)
				)
			)
		)
		(property "Value" "4K7R2F-GP"
			(at 0.064008 -3.993896 90)
			(unlocked yes)
			(layer "F.Fab")
			(hide yes)
			(effects
				(font
					(size 1.016 1.016)
					(thickness 0.1524)
				)
			)
		)
		(property "Device Type" "R402H16"
			(at 0.064008 -5.517896 90)
			(unlocked yes)
			(layer "F.Fab")
			(hide yes)
			(effects
				(font
					(size 1.016 1.016)
					(thickness 0.1524)
				)
			)
		)
		(duplicate_pad_numbers_are_jumpers no)
		(fp_line
			(start 0.508 -0.9398)
			(end -0.508 -0.9398)
			(stroke
				(width 0.1524)
				(type default)
			)
			(layer "F.SilkS")
		)
		(fp_line
			(start -0.508 -0.9398)
			(end -0.508 0.9398)
			(stroke
				(width 0.1524)
				(type default)
			)
			(layer "F.SilkS")
		)
		(fp_rect
			(start -0.508 0.9398)
			(end 0.508 -0.9398)
			(stroke
				(width 0)
				(type default)
			)
			(fill no)
			(layer "F.CrtYd")
		)
		(fp_rect
			(start -0.508 0.9398)
			(end 0.508 -0.9398)
			(stroke
				(width 0)
				(type default)
			)
			(fill no)
			(layer "F.Fab")
		)
		(pad "1" smd custom
			(at 0 -0.4445 90)
			(size 0.1397 0.1397)
			(layers "F.Cu" "F.Mask" "F.Paste")
			(net "IOC_EEPROM_A1")
			(options
				(clearance outline)
				(anchor circle)
			)
			(primitives
				(gr_poly
					(pts
						(arc
							(start -0.1778 -0.2794)
							(mid -0.249642 -0.249642)
							(end -0.2794 -0.1778)
						)
						(arc
							(start -0.2794 0.1778)
							(mid -0.249642 0.249642)
							(end -0.1778 0.2794)
						)
						(arc
							(start 0.1778 0.2794)
							(mid 0.249642 0.249642)
							(end 0.2794 0.1778)
						)
						(arc
							(start 0.2794 -0.1778)
							(mid 0.249642 -0.249642)
							(end 0.1778 -0.2794)
						)
					)
					(width 0)
					(fill yes)
				)
			)
		)
		(pad "2" smd custom
			(at 0 0.4445 90)
			(size 0.1397 0.1397)
			(layers "F.Cu" "F.Mask" "F.Paste")
			(net "GND")
			(options
				(clearance outline)
				(anchor circle)
			)
			(primitives
				(gr_poly
					(pts
						(arc
							(start -0.1778 -0.2794)
							(mid -0.249642 -0.249642)
							(end -0.2794 -0.1778)
						)
						(arc
							(start -0.2794 0.1778)
							(mid -0.249642 0.249642)
							(end -0.1778 0.2794)
						)
						(arc
							(start 0.1778 0.2794)
							(mid 0.249642 0.249642)
							(end 0.2794 0.1778)
						)
						(arc
							(start 0.2794 -0.1778)
							(mid 0.249642 -0.249642)
							(end 0.1778 -0.2794)
						)
					)
					(width 0)
					(fill yes)
				)
			)
		)
	)
)
